%FSTAX23Y23*%
%MOIN*%
%SFA1B1*%

%IPPOS*%
%ADD79R,0.314960X0.135830*%
%ADD80R,1.354330X0.230320*%
%ADD105R,0.036000X0.173000*%
%ADD106R,0.036000X0.134000*%
%ADD116R,0.065090X0.053280*%
%ADD118R,0.033200X0.034770*%
%ADD125R,0.053280X0.065090*%
%ADD126R,0.034770X0.033200*%
%ADD131R,0.090870X0.052090*%
%ADD133C,0.039500*%
%ADD134C,0.073980*%
%ADD135C,0.008000*%
%ADD136C,0.069020*%
%ADD137R,0.069020X0.069020*%
%ADD138C,0.083000*%
%ADD139C,0.106420*%
%ADD140O,0.096580X0.185170*%
%ADD141O,0.185170X0.096580*%
%ADD142O,0.204850X0.106420*%
%ADD143C,0.120000*%
%ADD144C,0.128000*%
%ADD145R,0.008000X0.008000*%
%ADD146C,0.029660*%
%ADD147C,0.063000*%
%ADD148R,0.063000X0.063000*%
%ADD149C,0.058000*%
%ADD150C,0.250000*%
%ADD151C,0.024000*%
%ADD152C,0.208000*%
%LNgrandmaster-1*%
%LPD*%
G54D79*
X0147Y00245D03*
G54D80*
X02446Y00111D03*
G54D105*
X01915Y00137D03*
X02545D03*
X02624D03*
X02899D03*
X03057D03*
X02742D03*
X02938D03*
X02781D03*
X02309D03*
X02427D03*
X02584D03*
X02072D03*
X02033D03*
X01994D03*
X01954D03*
X0219D03*
X02348D03*
X02387D03*
X02466D03*
X02505D03*
X0282D03*
X02663D03*
X0286D03*
X02978D03*
X03017D03*
X02702D03*
X02112D03*
X02151D03*
X01836D03*
X01875D03*
X03096D03*
G54D106*
X01797Y00157D03*
G54D116*
X02632Y02971D03*
Y03042D03*
G54D118*
X02349Y00329D03*
Y00362D03*
X02389D03*
Y00329D03*
X02468D03*
Y00362D03*
X02511D03*
Y00329D03*
X02664Y00362D03*
Y00329D03*
X02704Y00362D03*
Y00329D03*
X02819Y00362D03*
Y00329D03*
X02854D03*
Y00362D03*
X02979D03*
Y00329D03*
X03019Y00362D03*
Y00329D03*
X02711Y03003D03*
Y03036D03*
G54D125*
X02398Y02944D03*
X02327D03*
G54D126*
X02385Y02854D03*
X02351D03*
G54D131*
X02334Y03279D03*
Y032D03*
Y03121D03*
Y03042D03*
X02509Y03279D03*
Y03121D03*
Y032D03*
Y03042D03*
G54D133*
X03958Y04126D03*
X03784D03*
G54D134*
X03294Y04086D03*
X02994D03*
G54D135*
X02422Y03082D03*
Y03239D03*
Y03601D03*
Y03443D03*
G54D136*
X05327Y02307D03*
X05127D03*
X04927D03*
X04727D03*
X04927Y01007D03*
X05127D03*
X04327Y02307D03*
X05327Y01007D03*
G54D137*
X04327Y01007D03*
G54D138*
X05578Y0089D03*
Y01689D03*
Y02489D03*
X03979D03*
Y0089D03*
X04062Y02595D03*
X0418D03*
X04298D03*
G54D139*
X05723Y04025D03*
Y03844D03*
X069Y03806D03*
Y03589D03*
X06734D03*
Y03806D03*
X06569Y03589D03*
Y03806D03*
G54D140*
X05934Y03937D03*
G54D141*
X06119Y04056D03*
G54D142*
X06119Y03819D03*
G54D143*
X00199Y00906D03*
Y02481D03*
Y01956D03*
Y01431D03*
G54D144*
X00299Y01006D03*
Y00806D03*
X00099D03*
Y01006D03*
X00299Y02581D03*
Y02381D03*
X00099D03*
Y02581D03*
X00299Y02056D03*
Y01856D03*
X00099D03*
Y02056D03*
X00299Y01531D03*
Y01331D03*
X00099D03*
Y01531D03*
G54D145*
X03617Y02486D03*
X01652Y00916D03*
X01651Y02486D03*
X03617Y00916D03*
G54D146*
X03571Y02097D03*
Y01309D03*
X02203Y02438D03*
X01696Y01309D03*
Y02097D03*
X02203Y00958D03*
X0299D03*
X0299Y02438D03*
G54D147*
X02043Y04157D03*
Y04057D03*
X01457Y04153D03*
Y04053D03*
G54D148*
X02043Y04257D03*
X01457Y04253D03*
G54D149*
X069Y04093D03*
X06569D03*
G54D150*
X00285Y04152D03*
Y00368D03*
G54D151*
X02494Y02661D03*
X02692Y02721D03*
X02511Y00405D03*
X0261Y00279D03*
X02578D03*
X0298Y00409D03*
X02821Y00407D03*
X02748Y00282D03*
X02469Y0041D03*
X02905Y00279D03*
X02878Y00249D03*
X02692Y00795D03*
X02665D03*
X02854Y00405D03*
X02779Y00279D03*
X02665Y00405D03*
X02704D03*
X0235D03*
X02389D03*
X02937Y00279D03*
X02957Y00251D03*
X03019Y00405D03*
X0274Y00976D03*
X02767D03*
X02732Y00795D03*
X02681Y00976D03*
X02708D03*
X02447Y00242D03*
X02413Y00279D03*
X02444D03*
X02606Y00931D03*
X02625Y00795D03*
X02598D03*
X02636Y00247D03*
X02799Y00251D03*
X02826Y00976D03*
X02799D03*
X02649D03*
X02622D03*
X02759Y00795D03*
X02799D03*
X02826D03*
X02862D03*
X02893D03*
X02409Y01088D03*
X02311Y0109D03*
X02508Y00931D03*
X02409Y00932D03*
X02724Y01093D03*
X02784Y01094D03*
X02842Y01095D03*
X02546Y00244D03*
X03097Y00251D03*
X02475Y02291D03*
X0233Y02215D03*
X01798Y01304D03*
X02606Y01091D03*
X03554Y01841D03*
X03719Y01996D03*
X03894Y01566D03*
X03379Y01386D03*
X01721Y0189D03*
X01671Y01792D03*
X01674Y01989D03*
X02508Y0109D03*
X03413Y01573D03*
X0167Y01595D03*
X01754Y02126D03*
X02409Y02579D03*
X02586Y02569D03*
X03197Y01714D03*
X03439Y0187D03*
X03298Y01971D03*
X02985Y02287D03*
X02702Y02289D03*
X02821Y02601D03*
X01718Y01792D03*
X02881Y02566D03*
X03732Y01418D03*
X03554Y01891D03*
X02253Y02279D03*
X02272Y02463D03*
X01719Y01536D03*
X02311Y00934D03*
X03571Y02033D03*
X03554Y01991D03*
X02942Y02286D03*
X02841Y02263D03*
X02394Y0272D03*
X01567Y01285D03*
X01675Y01891D03*
X01568Y02067D03*
X02783Y02429D03*
X03719Y01921D03*
X03773Y01666D03*
X02599Y02436D03*
X02494Y02696D03*
X02894Y02431D03*
X02665Y01092D03*
X02475Y02456D03*
X03414Y01805D03*
X03404Y01363D03*
X02579Y02281D03*
X02685Y02311D03*
X0359Y01662D03*
X02404Y02412D03*
X02803Y02307D03*
X01716Y01399D03*
X01721Y01989D03*
X01619Y02121D03*
X03549Y01413D03*
X02488Y02413D03*
X02726Y02293D03*
X01822Y01674D03*
X0167Y01694D03*
X01884Y02071D03*
X02901Y01095D03*
X0292Y02428D03*
X01893Y01693D03*
X03594Y01514D03*
X0245Y02282D03*
X02409Y02314D03*
X02958Y02621D03*
X03406Y01461D03*
X0341Y01713D03*
X03252Y01661D03*
X02933Y00953D03*
X02871Y02297D03*
X02685Y02568D03*
X03571Y02058D03*
X03804Y0184D03*
X01879Y01811D03*
X03554Y01941D03*
X03392Y01871D03*
X03407Y01411D03*
X02575Y02412D03*
X02499Y02236D03*
X02409Y02283D03*
X02783Y02568D03*
X02948Y02456D03*
X03549Y01441D03*
X03718Y01713D03*
X02624Y02461D03*
X01897Y01516D03*
X03834Y01481D03*
X03864Y01511D03*
X03924Y01536D03*
X03719Y01766D03*
X03329Y01826D03*
X02645Y02274D03*
X02665Y02291D03*
X01721Y01694D03*
X01671Y01399D03*
X02581Y02308D03*
X03803Y01691D03*
X03224Y01661D03*
X02252Y02613D03*
X01718Y01497D03*
X01714Y01595D03*
X01671Y01497D03*
X02321Y02586D03*
X03379Y01336D03*
X01797Y00355D03*
X02034Y00246D03*
X01916Y00244D03*
X02309Y00246D03*
X0333Y03301D03*
X0412Y03594D03*
X01393Y01816D03*
X0099Y00687D03*
X04794Y02808D03*
X03183Y03135D03*
X03277Y02963D03*
X03197Y0297D03*
X03491Y03103D03*
X03188Y03187D03*
X0323Y03235D03*
X03358Y03448D03*
X03068Y03395D03*
X02419Y02788D03*
X02146Y02753D03*
X03275Y03141D03*
X03056Y01811D03*
X02413Y03295D03*
X02254Y03536D03*
X02579Y03486D03*
X02389Y03481D03*
X02321Y03361D03*
X02434Y03546D03*
X02634Y03406D03*
X02631Y02876D03*
X02591Y03186D03*
X0259Y03288D03*
X00996Y02256D03*
X02004Y01336D03*
X02028Y01361D03*
X02549Y01755D03*
X02418Y03118D03*
X02414Y03199D03*
X02462Y03172D03*
X02473Y0298D03*
X02146Y04103D03*
X02253Y04086D03*
X01408Y0398D03*
X01345Y04175D03*
X00996Y01187D03*
X00988Y01717D03*
X00937Y02317D03*
X02353Y04017D03*
X01726Y04329D03*
X01788D03*
X04477Y03135D03*
X04064Y02722D03*
X06628Y01372D03*
X04039Y02406D03*
X06974Y01939D03*
X04134Y01651D03*
X03994Y01551D03*
X04134Y01751D03*
X04151Y01623D03*
X03968Y01671D03*
X03969Y01552D03*
X03944Y01816D03*
X04131Y01686D03*
X04179Y01601D03*
X04034Y01546D03*
X03996Y01711D03*
X04064Y01796D03*
Y01511D03*
X03263Y03303D03*
X0396Y02724D03*
X01569Y04171D03*
X02076Y00255D03*
Y00287D03*
X02112D03*
X02151D03*
X02112Y00255D03*
X02151D03*
X01832D03*
X01852D03*
X01872D03*
X01832Y00287D03*
X01852D03*
X01872D03*
X06253Y02909D03*
X06647Y03129D03*
X05267Y04088D03*
X04339Y02725D03*
X04503Y02789D03*
X02231Y02584D03*
X05994Y03552D03*
X04049Y03665D03*
X03829Y03806D03*
X05577Y02214D03*
X02694Y01481D03*
X02384Y01941D03*
X0383Y03762D03*
X06334Y03266D03*
X03744Y03261D03*
X03395Y04222D03*
X04272Y03135D03*
X05634Y02236D03*
X02626Y0177D03*
X06304Y03121D03*
X03939D03*
X02139Y03738D03*
X04208Y03135D03*
X02604Y01734D03*
X06626Y03032D03*
X04152Y03135D03*
X02299Y01916D03*
X02724Y03521D03*
X01248Y02D03*
X02579Y0179D03*
X04068Y03135D03*
X02674Y03501D03*
X04234Y02725D03*
X06456Y03009D03*
X01691Y04079D03*
X03642Y00636D03*
X02259Y03261D03*
X03374Y03273D03*
X03368Y0305D03*
X04039Y03784D03*
X06476Y03231D03*
X04333Y03135D03*
X01557Y04229D03*
X06282Y03226D03*
X03806Y03235D03*
X01261Y02482D03*
X04114Y03135D03*
X06648Y03341D03*
X02888Y04221D03*
X0337Y02888D03*
X02258Y03741D03*
X01749Y0411D03*
X0257Y04283D03*
X01459Y03147D03*
X0144Y03557D03*
X01903Y04018D03*
X0229Y04217D03*
X0388Y03109D03*
X03623Y02587D03*
X03622Y03486D03*
X03491Y03297D03*
X03542Y03319D03*
X03344Y02996D03*
X03744Y03342D03*
X03653Y03293D03*
X03394Y03447D03*
X03436Y03457D03*
X03717Y03072D03*
X02799Y03616D03*
X03589Y01711D03*
X05733Y03556D03*
X05676Y03546D03*
X03603Y00682D03*
X02478Y00937D03*
X06548Y01531D03*
X06602Y01612D03*
Y01672D03*
Y01722D03*
X06601Y01777D03*
X06685Y01828D03*
X06699Y01881D03*
X06949Y02095D03*
X06607Y02176D03*
X06395Y02111D03*
X06048Y02171D03*
X06004Y02434D03*
X06274Y02391D03*
X06398Y02453D03*
X06397Y02501D03*
X06396Y02556D03*
X06397Y0261D03*
X06398Y02657D03*
X06372Y02909D03*
X0491Y04203D03*
X04387Y04206D03*
X03777Y04023D03*
X04085Y03892D03*
X04194Y03884D03*
X04431Y03135D03*
X0286Y03787D03*
X02724Y03729D03*
X03531Y0366D03*
X03269Y03788D03*
X01242Y01472D03*
X01256Y00942D03*
X00654Y0079D03*
X00655Y01028D03*
X00654Y01314D03*
X00653Y01551D03*
X00654Y01839D03*
Y02073D03*
Y02365D03*
X00653Y02593D03*
X02206Y01298D03*
X02205Y032D03*
X02502Y01316D03*
X02525Y02463D03*
X03342Y02263D03*
X03498Y02341D03*
X02429Y02621D03*
X01004Y00906D03*
X02446Y01437D03*
X01008Y0143D03*
X02409Y01967D03*
X01009Y01956D03*
X0102Y02481D03*
X02643Y01616D03*
X02666Y0164D03*
X01884Y03601D03*
X01754Y03661D03*
X03424Y03636D03*
X01549Y03621D03*
X03239Y03596D03*
X01574D03*
X03539Y03806D03*
X03219D03*
X02722Y03786D03*
X02139Y03611D03*
X02084Y03896D03*
X02083Y01411D03*
X02059Y01386D03*
Y03871D03*
X02029Y03836D03*
X01294Y04256D03*
X02004Y03816D03*
X02234Y03506D03*
X03529Y03481D03*
X05274Y03511D03*
X06284Y02501D03*
X02679Y03661D03*
X02774Y03566D03*
X02993Y03751D03*
X03699D03*
X03014Y03831D03*
X03699Y03836D03*
X04254Y03776D03*
X02894Y01561D03*
X02919Y01536D03*
X02274Y01506D03*
X02719Y01591D03*
X03724Y01675D03*
X06844Y01661D03*
X06424Y02181D03*
X06309Y03199D03*
X06339Y03151D03*
X04754Y04115D03*
X01779Y04156D03*
X03504Y04086D03*
X03854Y03151D03*
X03829Y03176D03*
X03799Y03201D03*
X06439Y03191D03*
X06354Y03331D03*
X06444Y03291D03*
X03302Y03344D03*
X06409Y03371D03*
X06447Y03396D03*
X06479Y03426D03*
X06509Y03456D03*
X03469D03*
X01849Y03701D03*
X06294D03*
G54D152*
X02531Y03853D03*
Y0283D03*
X00149D03*
Y03853D03*
M02*